(kicad_pcb
	(version 20260206)
	(generator "pcbnew")
	(generator_version "10.0")
	(general
		(thickness 1.6)
		(legacy_teardrops no)
	)
	(paper "A4")
	(title_block
		(title "01162023_DA0F0TEBIF0_F0T_Expander_BD_F_brd_V02_OCP.brd")
		(comment 1 "Grand Teton / footprints 7646-7653 of 9728")
	)
	(layers
		(0 "F.Cu" signal "TOP")
		(4 "In1.Cu" signal "GND")
		(6 "In2.Cu" signal "VCC")
		(8 "In3.Cu" signal "VCC1")
		(10 "In4.Cu" signal "GND1")
		(12 "In5.Cu" signal "IN1")
		(14 "In6.Cu" signal "GND2")
		(16 "In7.Cu" signal "IN2")
		(18 "In8.Cu" signal "GND3")
		(20 "In9.Cu" signal "IN3")
		(22 "In10.Cu" signal "GND4")
		(24 "In11.Cu" signal "IN4")
		(26 "In12.Cu" signal "GND5")
		(28 "In13.Cu" signal "IN5")
		(30 "In14.Cu" signal "GND6")
		(32 "In15.Cu" signal "IN6")
		(34 "In16.Cu" signal "GND7")
		(2 "B.Cu" signal "BOTTOM")
		(9 "F.Adhes" user "F.Adhesive")
		(11 "B.Adhes" user "B.Adhesive")
		(13 "F.Paste" user "Package Geometry/Pastemask Top")
		(15 "B.Paste" user "Package Geometry/Pastemask Bottom")
		(5 "F.SilkS" user "Ref Des/Silkscreen Top")
		(7 "B.SilkS" user "Ref Des/Silkscreen Bottom")
		(1 "F.Mask" user "Board Geometry/Soldermask Top")
		(3 "B.Mask" user "Board Geometry/Soldermask Bottom")
		(17 "Dwgs.User" user "User.Drawings")
		(19 "Cmts.User" user "User.Comments")
		(21 "Eco1.User" user "User.Eco1")
		(23 "Eco2.User" user "User.Eco2")
		(25 "Edge.Cuts" user "Board Geometry/Outline")
		(27 "Margin" user)
		(31 "F.CrtYd" user "Package Geometry/Place Bound Top")
		(29 "B.CrtYd" user "Package Geometry/Place Bound Bottom")
		(35 "F.Fab" user "Ref Des/Assembly Top")
		(33 "B.Fab" user "Ref Des/Assembly Bottom")
	)
	(footprint ""
		(layer "B.Cu")
		(at 101.744272 -327.980294)
		(property "Reference" "C2695"
			(at 0 0 0)
			(layer "B.SilkS")
			(hide yes)
			(effects
				(font
					(size 1.27 1.27)
				)
				(justify mirror)
			)
		)
		(property "Value" ""
			(at 0 0 0)
			(layer "B.Fab")
			(effects
				(font
					(size 1.27 1.27)
				)
				(justify mirror)
			)
		)
		(duplicate_pad_numbers_are_jumpers no)
		(fp_line
			(start -1.524 -0.762)
			(end -1.524 0.762)
			(stroke
				(width 0.1524)
				(type default)
			)
			(layer "B.SilkS")
		)
		(fp_line
			(start -1.524 0.762)
			(end 1.524 0.762)
			(stroke
				(width 0.1524)
				(type default)
			)
			(layer "B.SilkS")
		)
		(fp_line
			(start 1.524 -0.762)
			(end -1.524 -0.762)
			(stroke
				(width 0.1524)
				(type default)
			)
			(layer "B.SilkS")
		)
		(fp_line
			(start 1.524 0.762)
			(end 1.524 -0.762)
			(stroke
				(width 0.1524)
				(type default)
			)
			(layer "B.SilkS")
		)
		(fp_line
			(start -1.1049 -0.724916)
			(end 1.1049 -0.724916)
			(stroke
				(width 0.1)
				(type default)
			)
			(layer "B.Fab")
		)
		(fp_line
			(start -1.1049 0.724916)
			(end -1.1049 -0.724916)
			(stroke
				(width 0.1)
				(type default)
			)
			(layer "B.Fab")
		)
		(fp_line
			(start 1.1049 -0.724916)
			(end 1.1049 0.724916)
			(stroke
				(width 0.1)
				(type default)
			)
			(layer "B.Fab")
		)
		(fp_line
			(start 1.1049 0.724916)
			(end -1.1049 0.724916)
			(stroke
				(width 0.1)
				(type default)
			)
			(layer "B.Fab")
		)
		(pad "1" smd rect
			(at 0.889 0)
			(size 1.016 1.27)
			(layers "B.Cu" "B.Mask" "B.Paste")
			(net "P3V3_CLK_BUFFER_9ZXL0451E_VZX3P3")
		)
		(pad "2" smd rect
			(at -0.889 0)
			(size 1.016 1.27)
			(layers "B.Cu" "B.Mask" "B.Paste")
			(net "GND")
		)
	)
	(footprint ""
		(layer "B.Cu")
		(at 350.614488 -308.613556 90)
		(property "Reference" "C1924"
			(at 0 0 90)
			(layer "B.SilkS")
			(hide yes)
			(effects
				(font
					(size 1.27 1.27)
				)
				(justify mirror)
			)
		)
		(property "Value" ""
			(at 0 0 90)
			(layer "B.Fab")
			(effects
				(font
					(size 1.27 1.27)
				)
				(justify mirror)
			)
		)
		(duplicate_pad_numbers_are_jumpers no)
		(fp_line
			(start 1.2954 -0.5842)
			(end -1.2954 -0.5842)
			(stroke
				(width 0.1524)
				(type default)
			)
			(layer "B.SilkS")
		)
		(fp_line
			(start -1.2954 -0.5842)
			(end -1.2954 0.5842)
			(stroke
				(width 0.1524)
				(type default)
			)
			(layer "B.SilkS")
		)
		(fp_line
			(start 1.2954 0.5842)
			(end 1.2954 -0.5842)
			(stroke
				(width 0.1524)
				(type default)
			)
			(layer "B.SilkS")
		)
		(fp_line
			(start -1.2954 0.5842)
			(end 1.2954 0.5842)
			(stroke
				(width 0.1524)
				(type default)
			)
			(layer "B.SilkS")
		)
		(fp_line
			(start 0.8636 -0.4572)
			(end -0.8636 -0.4572)
			(stroke
				(width 0.1)
				(type default)
			)
			(layer "B.Fab")
		)
		(fp_line
			(start -0.8636 -0.4572)
			(end -0.8636 -0.4064)
			(stroke
				(width 0.1)
				(type default)
			)
			(layer "B.Fab")
		)
		(fp_line
			(start 1.1938 -0.4064)
			(end 0.8636 -0.4064)
			(stroke
				(width 0.1)
				(type default)
			)
			(layer "B.Fab")
		)
		(fp_line
			(start 0.8636 -0.4064)
			(end 0.8636 -0.4572)
			(stroke
				(width 0.1)
				(type default)
			)
			(layer "B.Fab")
		)
		(fp_line
			(start -0.8636 -0.4064)
			(end -1.1938 -0.4064)
			(stroke
				(width 0.1)
				(type default)
			)
			(layer "B.Fab")
		)
		(fp_line
			(start -1.1938 -0.4064)
			(end -1.1938 0.4064)
			(stroke
				(width 0.1)
				(type default)
			)
			(layer "B.Fab")
		)
		(fp_line
			(start 1.1938 0.4064)
			(end 1.1938 -0.4064)
			(stroke
				(width 0.1)
				(type default)
			)
			(layer "B.Fab")
		)
		(fp_line
			(start 0.8636 0.4064)
			(end 1.1938 0.4064)
			(stroke
				(width 0.1)
				(type default)
			)
			(layer "B.Fab")
		)
		(fp_line
			(start -0.8636 0.4064)
			(end -0.8636 0.4572)
			(stroke
				(width 0.1)
				(type default)
			)
			(layer "B.Fab")
		)
		(fp_line
			(start -1.1938 0.4064)
			(end -0.8636 0.4064)
			(stroke
				(width 0.1)
				(type default)
			)
			(layer "B.Fab")
		)
		(fp_line
			(start 0.8636 0.4572)
			(end 0.8636 0.4064)
			(stroke
				(width 0.1)
				(type default)
			)
			(layer "B.Fab")
		)
		(fp_line
			(start -0.8636 0.4572)
			(end 0.8636 0.4572)
			(stroke
				(width 0.1)
				(type default)
			)
			(layer "B.Fab")
		)
		(pad "1" smd rect
			(at 0.7366 0)
			(size 0.7112 0.8128)
			(layers "B.Cu" "B.Mask" "B.Paste")
			(net "P0V8_SERDES_VDDA_PEX3")
		)
		(pad "2" smd rect
			(at -0.7366 0)
			(size 0.7112 0.8128)
			(layers "B.Cu" "B.Mask" "B.Paste")
			(net "GND")
		)
	)
	(footprint ""
		(layer "B.Cu")
		(at 399.400014 -290.199826 90)
		(property "Reference" "C1940"
			(at 0 0 90)
			(layer "B.SilkS")
			(hide yes)
			(effects
				(font
					(size 1.27 1.27)
				)
				(justify mirror)
			)
		)
		(property "Value" ""
			(at 0 0 90)
			(layer "B.Fab")
			(effects
				(font
					(size 1.27 1.27)
				)
				(justify mirror)
			)
		)
		(duplicate_pad_numbers_are_jumpers no)
		(fp_line
			(start 0.299974 -0.150114)
			(end -0.299974 -0.150114)
			(stroke
				(width 0.1)
				(type default)
			)
			(layer "B.Fab")
		)
		(fp_line
			(start -0.299974 -0.150114)
			(end -0.299974 0.150114)
			(stroke
				(width 0.1)
				(type default)
			)
			(layer "B.Fab")
		)
		(fp_line
			(start 0.299974 0.150114)
			(end 0.299974 -0.150114)
			(stroke
				(width 0.1)
				(type default)
			)
			(layer "B.Fab")
		)
		(fp_line
			(start -0.299974 0.150114)
			(end 0.299974 0.150114)
			(stroke
				(width 0.1)
				(type default)
			)
			(layer "B.Fab")
		)
		(pad "1" smd rect
			(at 0.2667 0 270)
			(size 0.3048 0.381)
			(layers "B.Cu" "B.Mask" "B.Paste")
			(net "P0V8_SERDES_VDDA_PEX3")
		)
		(pad "2" smd rect
			(at -0.2667 0 270)
			(size 0.3048 0.381)
			(layers "B.Cu" "B.Mask" "B.Paste")
			(net "GND")
		)
	)
	(footprint ""
		(layer "B.Cu")
		(at 128.432814 -177.14087)
		(property "Reference" "C2656"
			(at 0 0 0)
			(layer "B.SilkS")
			(hide yes)
			(effects
				(font
					(size 1.27 1.27)
				)
				(justify mirror)
			)
		)
		(property "Value" ""
			(at 0 0 0)
			(layer "B.Fab")
			(effects
				(font
					(size 1.27 1.27)
				)
				(justify mirror)
			)
		)
		(duplicate_pad_numbers_are_jumpers no)
		(fp_line
			(start -0.7874 -0.4064)
			(end -0.7874 0.4064)
			(stroke
				(width 0.1524)
				(type default)
			)
			(layer "B.SilkS")
		)
		(fp_line
			(start -0.7874 0.4064)
			(end 0.7874 0.4064)
			(stroke
				(width 0.1524)
				(type default)
			)
			(layer "B.SilkS")
		)
		(fp_line
			(start 0.7874 -0.4064)
			(end -0.7874 -0.4064)
			(stroke
				(width 0.1524)
				(type default)
			)
			(layer "B.SilkS")
		)
		(fp_line
			(start 0.7874 0.4064)
			(end 0.7874 -0.4064)
			(stroke
				(width 0.1524)
				(type default)
			)
			(layer "B.SilkS")
		)
		(fp_line
			(start -0.67945 -0.3048)
			(end -0.67945 0.3048)
			(stroke
				(width 0.1)
				(type default)
			)
			(layer "B.Fab")
		)
		(fp_line
			(start -0.67945 0.3048)
			(end -0.120396 0.3048)
			(stroke
				(width 0.1)
				(type default)
			)
			(layer "B.Fab")
		)
		(fp_line
			(start -0.12065 -0.3048)
			(end -0.67945 -0.3048)
			(stroke
				(width 0.1)
				(type default)
			)
			(layer "B.Fab")
		)
		(fp_line
			(start -0.12065 -0.2794)
			(end -0.12065 -0.3048)
			(stroke
				(width 0.1)
				(type default)
			)
			(layer "B.Fab")
		)
		(fp_line
			(start -0.120396 0.2794)
			(end 0.12065 0.2794)
			(stroke
				(width 0.1)
				(type default)
			)
			(layer "B.Fab")
		)
		(fp_line
			(start -0.120396 0.3048)
			(end -0.120396 0.2794)
			(stroke
				(width 0.1)
				(type default)
			)
			(layer "B.Fab")
		)
		(fp_line
			(start 0.12065 -0.305054)
			(end 0.12065 -0.2794)
			(stroke
				(width 0.1)
				(type default)
			)
			(layer "B.Fab")
		)
		(fp_line
			(start 0.12065 -0.2794)
			(end -0.12065 -0.2794)
			(stroke
				(width 0.1)
				(type default)
			)
			(layer "B.Fab")
		)
		(fp_line
			(start 0.12065 0.2794)
			(end 0.12065 0.3048)
			(stroke
				(width 0.1)
				(type default)
			)
			(layer "B.Fab")
		)
		(fp_line
			(start 0.12065 0.3048)
			(end 0.67945 0.3048)
			(stroke
				(width 0.1)
				(type default)
			)
			(layer "B.Fab")
		)
		(fp_line
			(start 0.67945 -0.305054)
			(end 0.12065 -0.305054)
			(stroke
				(width 0.1)
				(type default)
			)
			(layer "B.Fab")
		)
		(fp_line
			(start 0.67945 0.3048)
			(end 0.67945 -0.305054)
			(stroke
				(width 0.1)
				(type default)
			)
			(layer "B.Fab")
		)
		(pad "1" smd circle
			(at 0.40005 0 180)
			(size 0 0)
			(layers "B.Cu" "B.Mask" "B.Paste")
			(net "P3V3_DB2000QL_VDDR")
		)
		(pad "2" smd circle
			(at -0.40005 0 180)
			(size 0 0)
			(layers "B.Cu" "B.Mask" "B.Paste")
			(net "GND")
		)
	)
	(footprint ""
		(layer "B.Cu")
		(at 173.53026 -295.221914)
		(property "Reference" "C1355"
			(at 0 0 0)
			(layer "B.SilkS")
			(hide yes)
			(effects
				(font
					(size 1.27 1.27)
				)
				(justify mirror)
			)
		)
		(property "Value" ""
			(at 0 0 0)
			(layer "B.Fab")
			(effects
				(font
					(size 1.27 1.27)
				)
				(justify mirror)
			)
		)
		(duplicate_pad_numbers_are_jumpers no)
		(fp_line
			(start -1.2954 -0.5842)
			(end -1.2954 0.5842)
			(stroke
				(width 0.1524)
				(type default)
			)
			(layer "B.SilkS")
		)
		(fp_line
			(start -1.2954 0.5842)
			(end 1.2954 0.5842)
			(stroke
				(width 0.1524)
				(type default)
			)
			(layer "B.SilkS")
		)
		(fp_line
			(start 1.2954 -0.5842)
			(end -1.2954 -0.5842)
			(stroke
				(width 0.1524)
				(type default)
			)
			(layer "B.SilkS")
		)
		(fp_line
			(start 1.2954 0.5842)
			(end 1.2954 -0.5842)
			(stroke
				(width 0.1524)
				(type default)
			)
			(layer "B.SilkS")
		)
		(fp_line
			(start -1.1938 -0.4064)
			(end -1.1938 0.4064)
			(stroke
				(width 0.1)
				(type default)
			)
			(layer "B.Fab")
		)
		(fp_line
			(start -1.1938 0.4064)
			(end -0.8636 0.4064)
			(stroke
				(width 0.1)
				(type default)
			)
			(layer "B.Fab")
		)
		(fp_line
			(start -0.8636 -0.4572)
			(end -0.8636 -0.4064)
			(stroke
				(width 0.1)
				(type default)
			)
			(layer "B.Fab")
		)
		(fp_line
			(start -0.8636 -0.4064)
			(end -1.1938 -0.4064)
			(stroke
				(width 0.1)
				(type default)
			)
			(layer "B.Fab")
		)
		(fp_line
			(start -0.8636 0.4064)
			(end -0.8636 0.4572)
			(stroke
				(width 0.1)
				(type default)
			)
			(layer "B.Fab")
		)
		(fp_line
			(start -0.8636 0.4572)
			(end 0.8636 0.4572)
			(stroke
				(width 0.1)
				(type default)
			)
			(layer "B.Fab")
		)
		(fp_line
			(start 0.8636 -0.4572)
			(end -0.8636 -0.4572)
			(stroke
				(width 0.1)
				(type default)
			)
			(layer "B.Fab")
		)
		(fp_line
			(start 0.8636 -0.4064)
			(end 0.8636 -0.4572)
			(stroke
				(width 0.1)
				(type default)
			)
			(layer "B.Fab")
		)
		(fp_line
			(start 0.8636 0.4064)
			(end 1.1938 0.4064)
			(stroke
				(width 0.1)
				(type default)
			)
			(layer "B.Fab")
		)
		(fp_line
			(start 0.8636 0.4572)
			(end 0.8636 0.4064)
			(stroke
				(width 0.1)
				(type default)
			)
			(layer "B.Fab")
		)
		(fp_line
			(start 1.1938 -0.4064)
			(end 0.8636 -0.4064)
			(stroke
				(width 0.1)
				(type default)
			)
			(layer "B.Fab")
		)
		(fp_line
			(start 1.1938 0.4064)
			(end 1.1938 -0.4064)
			(stroke
				(width 0.1)
				(type default)
			)
			(layer "B.Fab")
		)
		(pad "1" smd rect
			(at 0.7366 0 270)
			(size 0.7112 0.8128)
			(layers "B.Cu" "B.Mask" "B.Paste")
			(net "P0V8_PEX1")
		)
		(pad "2" smd rect
			(at -0.7366 0 270)
			(size 0.7112 0.8128)
			(layers "B.Cu" "B.Mask" "B.Paste")
			(net "GND")
		)
	)
	(footprint ""
		(layer "B.Cu")
		(at 344.778838 -281.024838 90)
		(property "Reference" "PC160"
			(at 0 0 90)
			(layer "B.SilkS")
			(hide yes)
			(effects
				(font
					(size 1.27 1.27)
				)
				(justify mirror)
			)
		)
		(property "Value" ""
			(at 0 0 90)
			(layer "B.Fab")
			(effects
				(font
					(size 1.27 1.27)
				)
				(justify mirror)
			)
		)
		(duplicate_pad_numbers_are_jumpers no)
		(fp_line
			(start 1.524 -0.762)
			(end -1.524 -0.762)
			(stroke
				(width 0.1524)
				(type default)
			)
			(layer "B.SilkS")
		)
		(fp_line
			(start -1.524 -0.762)
			(end -1.524 0.762)
			(stroke
				(width 0.1524)
				(type default)
			)
			(layer "B.SilkS")
		)
		(fp_line
			(start 1.524 0.762)
			(end 1.524 -0.762)
			(stroke
				(width 0.1524)
				(type default)
			)
			(layer "B.SilkS")
		)
		(fp_line
			(start -1.524 0.762)
			(end 1.524 0.762)
			(stroke
				(width 0.1524)
				(type default)
			)
			(layer "B.SilkS")
		)
		(fp_line
			(start 1.1049 -0.724916)
			(end 1.1049 0.724916)
			(stroke
				(width 0.1)
				(type default)
			)
			(layer "B.Fab")
		)
		(fp_line
			(start -1.1049 -0.724916)
			(end 1.1049 -0.724916)
			(stroke
				(width 0.1)
				(type default)
			)
			(layer "B.Fab")
		)
		(fp_line
			(start 1.1049 0.724916)
			(end -1.1049 0.724916)
			(stroke
				(width 0.1)
				(type default)
			)
			(layer "B.Fab")
		)
		(fp_line
			(start -1.1049 0.724916)
			(end -1.1049 -0.724916)
			(stroke
				(width 0.1)
				(type default)
			)
			(layer "B.Fab")
		)
		(pad "1" smd rect
			(at 0.889 0 90)
			(size 1.016 1.27)
			(layers "B.Cu" "B.Mask" "B.Paste")
			(net "SW_P12V_P0V8_PEX2_FLT")
		)
		(pad "2" smd rect
			(at -0.889 0 90)
			(size 1.016 1.27)
			(layers "B.Cu" "B.Mask" "B.Paste")
			(net "GND")
		)
	)
	(footprint ""
		(layer "B.Cu")
		(at 228.531928 -284.252162 180)
		(property "Reference" "PC234"
			(at 0 0 0)
			(layer "B.SilkS")
			(hide yes)
			(effects
				(font
					(size 1.27 1.27)
				)
				(justify mirror)
			)
		)
		(property "Value" ""
			(at 0 0 0)
			(layer "B.Fab")
			(effects
				(font
					(size 1.27 1.27)
				)
				(justify mirror)
			)
		)
		(duplicate_pad_numbers_are_jumpers no)
		(fp_line
			(start 1.524 0.762)
			(end 1.524 -0.762)
			(stroke
				(width 0.1524)
				(type default)
			)
			(layer "B.SilkS")
		)
		(fp_line
			(start 1.524 -0.762)
			(end -1.524 -0.762)
			(stroke
				(width 0.1524)
				(type default)
			)
			(layer "B.SilkS")
		)
		(fp_line
			(start -1.524 0.762)
			(end 1.524 0.762)
			(stroke
				(width 0.1524)
				(type default)
			)
			(layer "B.SilkS")
		)
		(fp_line
			(start -1.524 -0.762)
			(end -1.524 0.762)
			(stroke
				(width 0.1524)
				(type default)
			)
			(layer "B.SilkS")
		)
		(fp_line
			(start 1.1049 0.724916)
			(end -1.1049 0.724916)
			(stroke
				(width 0.1)
				(type default)
			)
			(layer "B.Fab")
		)
		(fp_line
			(start 1.1049 -0.724916)
			(end 1.1049 0.724916)
			(stroke
				(width 0.1)
				(type default)
			)
			(layer "B.Fab")
		)
		(fp_line
			(start -1.1049 0.724916)
			(end -1.1049 -0.724916)
			(stroke
				(width 0.1)
				(type default)
			)
			(layer "B.Fab")
		)
		(fp_line
			(start -1.1049 -0.724916)
			(end 1.1049 -0.724916)
			(stroke
				(width 0.1)
				(type default)
			)
			(layer "B.Fab")
		)
		(pad "1" smd rect
			(at 0.889 0 180)
			(size 1.016 1.27)
			(layers "B.Cu" "B.Mask" "B.Paste")
			(net "P1V25_PEX1_R")
		)
		(pad "2" smd rect
			(at -0.889 0 180)
			(size 1.016 1.27)
			(layers "B.Cu" "B.Mask" "B.Paste")
			(net "GND")
		)
	)
	(footprint ""
		(layer "B.Cu")
		(at 320.60642 -83.123278 180)
		(property "Reference" "R1764"
			(at 0 0 0)
			(layer "B.SilkS")
			(hide yes)
			(effects
				(font
					(size 1.27 1.27)
				)
				(justify mirror)
			)
		)
		(property "Value" ""
			(at 0 0 0)
			(layer "B.Fab")
			(effects
				(font
					(size 1.27 1.27)
				)
				(justify mirror)
			)
		)
		(duplicate_pad_numbers_are_jumpers no)
		(fp_line
			(start 0.7874 0.4064)
			(end 0.7874 -0.4064)
			(stroke
				(width 0.1524)
				(type default)
			)
			(layer "B.SilkS")
		)
		(fp_line
			(start 0.7874 -0.4064)
			(end -0.7874 -0.4064)
			(stroke
				(width 0.1524)
				(type default)
			)
			(layer "B.SilkS")
		)
		(fp_line
			(start -0.7874 0.4064)
			(end 0.7874 0.4064)
			(stroke
				(width 0.1524)
				(type default)
			)
			(layer "B.SilkS")
		)
		(fp_line
			(start -0.7874 -0.4064)
			(end -0.7874 0.4064)
			(stroke
				(width 0.1524)
				(type default)
			)
			(layer "B.SilkS")
		)
		(fp_line
			(start 0.67945 0.3048)
			(end 0.67945 -0.305054)
			(stroke
				(width 0.1)
				(type default)
			)
			(layer "B.Fab")
		)
		(fp_line
			(start 0.67945 -0.305054)
			(end 0.12065 -0.305054)
			(stroke
				(width 0.1)
				(type default)
			)
			(layer "B.Fab")
		)
		(fp_line
			(start 0.12065 0.3048)
			(end 0.67945 0.3048)
			(stroke
				(width 0.1)
				(type default)
			)
			(layer "B.Fab")
		)
		(fp_line
			(start 0.12065 0.2794)
			(end 0.12065 0.3048)
			(stroke
				(width 0.1)
				(type default)
			)
			(layer "B.Fab")
		)
		(fp_line
			(start 0.12065 -0.2794)
			(end -0.12065 -0.2794)
			(stroke
				(width 0.1)
				(type default)
			)
			(layer "B.Fab")
		)
		(fp_line
			(start 0.12065 -0.305054)
			(end 0.12065 -0.2794)
			(stroke
				(width 0.1)
				(type default)
			)
			(layer "B.Fab")
		)
		(fp_line
			(start -0.120396 0.3048)
			(end -0.120396 0.2794)
			(stroke
				(width 0.1)
				(type default)
			)
			(layer "B.Fab")
		)
		(fp_line
			(start -0.120396 0.2794)
			(end 0.12065 0.2794)
			(stroke
				(width 0.1)
				(type default)
			)
			(layer "B.Fab")
		)
		(fp_line
			(start -0.12065 -0.2794)
			(end -0.12065 -0.3048)
			(stroke
				(width 0.1)
				(type default)
			)
			(layer "B.Fab")
		)
		(fp_line
			(start -0.12065 -0.3048)
			(end -0.67945 -0.3048)
			(stroke
				(width 0.1)
				(type default)
			)
			(layer "B.Fab")
		)
		(fp_line
			(start -0.67945 0.3048)
			(end -0.120396 0.3048)
			(stroke
				(width 0.1)
				(type default)
			)
			(layer "B.Fab")
		)
		(fp_line
			(start -0.67945 -0.3048)
			(end -0.67945 0.3048)
			(stroke
				(width 0.1)
				(type default)
			)
			(layer "B.Fab")
		)
		(pad "1" smd circle
			(at 0.40005 0)
			(size 0 0)
			(layers "B.Cu" "B.Mask" "B.Paste")
			(net "P3V3_AUX")
		)
		(pad "2" smd circle
			(at -0.40005 0)
			(size 0 0)
			(layers "B.Cu" "B.Mask" "B.Paste")
			(net "SMB_BIC_I2C6_MUX_FRU_R_SCL")
		)
	)
)
